(kicad_pcb
	(version 20221018)
	(generator pcbnew)
	(general
    (thickness 1.7403)
  )
	(paper "A4")
	(title_block
    (title "Data Center RDIMM DDR4 Tester")
    (date "2024-09-30")
    (rev "1.2.4")
		(comment 9 "footprint 169 of 690 (U14), pads 114-224 of 291")
	)
	(layers
    (0 "F.Cu" signal)
    (1 "In1.Cu" power)
    (2 "In2.Cu" signal)
    (3 "In3.Cu" power)
    (4 "In4.Cu" power)
    (5 "In5.Cu" signal)
    (6 "In6.Cu" power)
    (7 "In7.Cu" signal)
    (8 "In8.Cu" power)
    (9 "In9.Cu" signal)
    (10 "In10.Cu" power)
    (31 "B.Cu" signal)
    (32 "B.Adhes" user "B.Adhesive")
    (33 "F.Adhes" user "F.Adhesive")
    (34 "B.Paste" user)
    (35 "F.Paste" user)
    (36 "B.SilkS" user "B.Silkscreen")
    (37 "F.SilkS" user "F.Silkscreen")
    (38 "B.Mask" user)
    (39 "F.Mask" user)
    (40 "Dwgs.User" user "User.Drawings")
    (41 "Cmts.User" user "User.Comments")
    (42 "Eco1.User" user "User.Eco1")
    (43 "Eco2.User" user "User.Eco2")
    (44 "Edge.Cuts" user)
    (45 "Margin" user)
    (46 "B.CrtYd" user "B.Courtyard")
    (47 "F.CrtYd" user "F.Courtyard")
    (48 "B.Fab" user)
    (49 "F.Fab" user)
  )
	(footprint "data-center-rdimm-ddr4-tester-footprints:Bus_DDR4_Socket_DIMM_2199155-1"
    (layer "F.Cu")
    (at 246.636328 55.060008 180)
    (property "Author" "Antmicro")
    (property "License" "Apache-2.0")
    (property "MPN" "2199155-1")
    (property "Manufacturer" "TE Connectivity")
    (property "Sheetfile" "DDR4.kicad_sch")
    (property "Sheetname" "DDR4")
    (property "ki_description" "DDR4 RDIMM 288 Pin SMT type")
    (attr smd)
    (fp_text reference "U14" (at -5.583672 1.360008 180) (layer "F.SilkS")
        (effects (font (size 0.7 0.7) (thickness 0.15)) (justify left bottom))
    )
    (fp_text value "Bus_DDR4_2199155-1" (at -7.9 2.3 180) (layer "F.Fab") hide
        (effects (font (size 0.7 0.7) (thickness 0.15)) (justify left bottom))
    )
    (pad "114" smd rect (at 101.15 0 270) (size 1.8 0.57) (layers "F.Cu" "F.Paste" "F.Mask")
      (net 9 "GND") (pinfunction "VSS") (pintype "passive"))
    (pad "115" smd rect (at 101.998 0 270) (size 1.8 0.57) (layers "F.Cu" "F.Paste" "F.Mask")
      (net 224 "DQ42") (pinfunction "DQ42") (pintype "passive"))
    (pad "116" smd rect (at 102.849 0 270) (size 1.8 0.57) (layers "F.Cu" "F.Paste" "F.Mask")
      (net 9 "GND") (pinfunction "VSS") (pintype "passive"))
    (pad "117" smd rect (at 103.7 0 270) (size 1.8 0.57) (layers "F.Cu" "F.Paste" "F.Mask")
      (net 223 "DQ52") (pinfunction "DQ52") (pintype "passive"))
    (pad "118" smd rect (at 104.549 0 270) (size 1.8 0.57) (layers "F.Cu" "F.Paste" "F.Mask")
      (net 9 "GND") (pinfunction "VSS") (pintype "passive"))
    (pad "119" smd rect (at 105.4 0 270) (size 1.8 0.57) (layers "F.Cu" "F.Paste" "F.Mask")
      (net 225 "DQ48") (pinfunction "DQ48") (pintype "passive"))
    (pad "120" smd rect (at 106.248 0 270) (size 1.8 0.57) (layers "F.Cu" "F.Paste" "F.Mask")
      (net 9 "GND") (pinfunction "VSS") (pintype "passive"))
    (pad "121" smd rect (at 107.099 0 270) (size 1.8 0.57) (layers "F.Cu" "F.Paste" "F.Mask")
      (net 339 "DQS15_P") (pinfunction "DQS15_t") (pintype "passive"))
    (pad "122" smd rect (at 107.95 0 270) (size 1.8 0.57) (layers "F.Cu" "F.Paste" "F.Mask")
      (net 341 "DQS15_N") (pinfunction "DQS15_c") (pintype "passive"))
    (pad "123" smd rect (at 108.799 0 270) (size 1.8 0.57) (layers "F.Cu" "F.Paste" "F.Mask")
      (net 9 "GND") (pinfunction "VSS") (pintype "passive"))
    (pad "124" smd rect (at 109.65 0 270) (size 1.8 0.57) (layers "F.Cu" "F.Paste" "F.Mask")
      (net 220 "DQ54") (pinfunction "DQ54") (pintype "passive"))
    (pad "125" smd rect (at 110.498 0 270) (size 1.8 0.57) (layers "F.Cu" "F.Paste" "F.Mask")
      (net 9 "GND") (pinfunction "VSS") (pintype "passive"))
    (pad "126" smd rect (at 111.349 0 270) (size 1.8 0.57) (layers "F.Cu" "F.Paste" "F.Mask")
      (net 219 "DQ50") (pinfunction "DQ50") (pintype "passive"))
    (pad "127" smd rect (at 112.2 0 270) (size 1.8 0.57) (layers "F.Cu" "F.Paste" "F.Mask")
      (net 9 "GND") (pinfunction "VSS") (pintype "passive"))
    (pad "128" smd rect (at 113.049 0 270) (size 1.8 0.57) (layers "F.Cu" "F.Paste" "F.Mask")
      (net 221 "DQ60") (pinfunction "DQ60") (pintype "passive"))
    (pad "129" smd rect (at 113.9 0 270) (size 1.8 0.57) (layers "F.Cu" "F.Paste" "F.Mask")
      (net 9 "GND") (pinfunction "VSS") (pintype "passive"))
    (pad "130" smd rect (at 114.749 0 270) (size 1.8 0.57) (layers "F.Cu" "F.Paste" "F.Mask")
      (net 215 "DQ56") (pinfunction "DQ56") (pintype "passive"))
    (pad "131" smd rect (at 115.599 0 270) (size 1.8 0.57) (layers "F.Cu" "F.Paste" "F.Mask")
      (net 9 "GND") (pinfunction "VSS") (pintype "passive"))
    (pad "132" smd rect (at 116.45 0 270) (size 1.8 0.57) (layers "F.Cu" "F.Paste" "F.Mask")
      (net 343 "DQS16_P") (pinfunction "DQS16_t") (pintype "passive"))
    (pad "133" smd rect (at 117.299 0 270) (size 1.8 0.57) (layers "F.Cu" "F.Paste" "F.Mask")
      (net 345 "DQS16_N") (pinfunction "DQS16_c") (pintype "passive"))
    (pad "134" smd rect (at 118.15 0 270) (size 1.8 0.57) (layers "F.Cu" "F.Paste" "F.Mask")
      (net 9 "GND") (pinfunction "VSS") (pintype "passive"))
    (pad "135" smd rect (at 118.999 0 270) (size 1.8 0.57) (layers "F.Cu" "F.Paste" "F.Mask")
      (net 217 "DQ62") (pinfunction "DQ62") (pintype "passive"))
    (pad "136" smd rect (at 119.849 0 270) (size 1.8 0.57) (layers "F.Cu" "F.Paste" "F.Mask")
      (net 9 "GND") (pinfunction "VSS") (pintype "passive"))
    (pad "137" smd rect (at 120.7 0 270) (size 1.8 0.57) (layers "F.Cu" "F.Paste" "F.Mask")
      (net 216 "DQ58") (pinfunction "DQ58") (pintype "passive"))
    (pad "138" smd rect (at 121.549 0 270) (size 1.8 0.57) (layers "F.Cu" "F.Paste" "F.Mask")
      (net 9 "GND") (pinfunction "VSS") (pintype "passive"))
    (pad "139" smd rect (at 122.4 0 270) (size 1.8 0.57) (layers "F.Cu" "F.Paste" "F.Mask")
      (net 218 "SA0") (pinfunction "SA0") (pintype "passive"))
    (pad "140" smd rect (at 123.249 0 270) (size 1.8 0.57) (layers "F.Cu" "F.Paste" "F.Mask")
      (net 214 "SA1") (pinfunction "SA1") (pintype "passive"))
    (pad "141" smd rect (at 124.099 0 270) (size 1.8 0.57) (layers "F.Cu" "F.Paste" "F.Mask")
      (net 351 "SCL_2V5") (pinfunction "SCL") (pintype "passive"))
    (pad "142" smd rect (at 124.95 0 270) (size 1.8 0.57) (layers "F.Cu" "F.Paste" "F.Mask")
      (net 184 "VPP") (pinfunction "VPP") (pintype "passive"))
    (pad "143" smd rect (at 125.799 0 270) (size 1.8 0.57) (layers "F.Cu" "F.Paste" "F.Mask")
      (net 184 "VPP") (pinfunction "VPP") (pintype "passive"))
    (pad "144" smd rect (at 126.65 0 270) (size 1.8 0.57) (layers "F.Cu" "F.Paste" "F.Mask")
      (net 705 "unconnected-(U14B-RFU-Pad144)") (pinfunction "RFU") (pintype "no_connect"))
    (pad "145" smd rect (at 0 -4.601 270) (size 1.8 0.57) (layers "F.Cu" "F.Paste" "F.Mask")
      (net 308 "NC") (pinfunction "12V/NC") (pintype "passive"))
    (pad "146" smd rect (at 0.848 -4.601 270) (size 1.8 0.57) (layers "F.Cu" "F.Paste" "F.Mask")
      (net 400 "VREFCA") (pinfunction "VREFCA") (pintype "passive"))
    (pad "147" smd rect (at 1.699 -4.601 270) (size 1.8 0.57) (layers "F.Cu" "F.Paste" "F.Mask")
      (net 9 "GND") (pinfunction "VSS") (pintype "passive"))
    (pad "148" smd rect (at 2.548 -4.601 270) (size 1.8 0.57) (layers "F.Cu" "F.Paste" "F.Mask")
      (net 298 "DQ5") (pinfunction "DQ5") (pintype "passive"))
    (pad "149" smd rect (at 3.398 -4.601 270) (size 1.8 0.57) (layers "F.Cu" "F.Paste" "F.Mask")
      (net 9 "GND") (pinfunction "VSS") (pintype "passive"))
    (pad "150" smd rect (at 4.248 -4.601 270) (size 1.8 0.57) (layers "F.Cu" "F.Paste" "F.Mask")
      (net 288 "DQ1") (pinfunction "DQ1") (pintype "passive"))
    (pad "151" smd rect (at 5.099 -4.601 270) (size 1.8 0.57) (layers "F.Cu" "F.Paste" "F.Mask")
      (net 9 "GND") (pinfunction "VSS") (pintype "passive"))
    (pad "152" smd rect (at 5.95 -4.601 270) (size 1.8 0.57) (layers "F.Cu" "F.Paste" "F.Mask")
      (net 315 "DQS0_N") (pinfunction "DQS0_c") (pintype "passive"))
    (pad "153" smd rect (at 6.799 -4.601 270) (size 1.8 0.57) (layers "F.Cu" "F.Paste" "F.Mask")
      (net 314 "DQS0_P") (pinfunction "DQS0_t") (pintype "passive"))
    (pad "154" smd rect (at 7.65 -4.601 270) (size 1.8 0.57) (layers "F.Cu" "F.Paste" "F.Mask")
      (net 9 "GND") (pinfunction "VSS") (pintype "passive"))
    (pad "155" smd rect (at 8.499 -4.601 270) (size 1.8 0.57) (layers "F.Cu" "F.Paste" "F.Mask")
      (net 297 "DQ7") (pinfunction "DQ7") (pintype "passive"))
    (pad "156" smd rect (at 9.349 -4.601 270) (size 1.8 0.57) (layers "F.Cu" "F.Paste" "F.Mask")
      (net 9 "GND") (pinfunction "VSS") (pintype "passive"))
    (pad "157" smd rect (at 10.198 -4.601 270) (size 1.8 0.57) (layers "F.Cu" "F.Paste" "F.Mask")
      (net 292 "DQ3") (pinfunction "DQ3") (pintype "passive"))
    (pad "158" smd rect (at 11.05 -4.601 270) (size 1.8 0.57) (layers "F.Cu" "F.Paste" "F.Mask")
      (net 9 "GND") (pinfunction "VSS") (pintype "passive"))
    (pad "159" smd rect (at 11.9 -4.601 270) (size 1.8 0.57) (layers "F.Cu" "F.Paste" "F.Mask")
      (net 275 "DQ13") (pinfunction "DQ13") (pintype "passive"))
    (pad "160" smd rect (at 12.749 -4.601 270) (size 1.8 0.57) (layers "F.Cu" "F.Paste" "F.Mask")
      (net 9 "GND") (pinfunction "VSS") (pintype "passive"))
    (pad "161" smd rect (at 13.598 -4.601 270) (size 1.8 0.57) (layers "F.Cu" "F.Paste" "F.Mask")
      (net 293 "DQ9") (pinfunction "DQ9") (pintype "passive"))
    (pad "162" smd rect (at 14.448 -4.601 270) (size 1.8 0.57) (layers "F.Cu" "F.Paste" "F.Mask")
      (net 9 "GND") (pinfunction "VSS") (pintype "passive"))
    (pad "163" smd rect (at 15.3 -4.601 270) (size 1.8 0.57) (layers "F.Cu" "F.Paste" "F.Mask")
      (net 320 "DQS1_N") (pinfunction "DQS1_c") (pintype "passive"))
    (pad "164" smd rect (at 16.149 -4.601 270) (size 1.8 0.57) (layers "F.Cu" "F.Paste" "F.Mask")
      (net 318 "DQS1_P") (pinfunction "DQS_1_t") (pintype "passive"))
    (pad "165" smd rect (at 16.998 -4.601 270) (size 1.8 0.57) (layers "F.Cu" "F.Paste" "F.Mask")
      (net 9 "GND") (pinfunction "VSS") (pintype "passive"))
    (pad "166" smd rect (at 17.85 -4.601 270) (size 1.8 0.57) (layers "F.Cu" "F.Paste" "F.Mask")
      (net 273 "DQ15") (pinfunction "DQ15") (pintype "passive"))
    (pad "167" smd rect (at 18.699 -4.601 270) (size 1.8 0.57) (layers "F.Cu" "F.Paste" "F.Mask")
      (net 9 "GND") (pinfunction "VSS") (pintype "passive"))
    (pad "168" smd rect (at 19.55 -4.601 270) (size 1.8 0.57) (layers "F.Cu" "F.Paste" "F.Mask")
      (net 274 "DQ11") (pinfunction "DQ11") (pintype "passive"))
    (pad "169" smd rect (at 20.399 -4.601 270) (size 1.8 0.57) (layers "F.Cu" "F.Paste" "F.Mask")
      (net 9 "GND") (pinfunction "VSS") (pintype "passive"))
    (pad "170" smd rect (at 21.248 -4.601 270) (size 1.8 0.57) (layers "F.Cu" "F.Paste" "F.Mask")
      (net 294 "DQ21") (pinfunction "DQ21") (pintype "passive"))
    (pad "171" smd rect (at 22.1 -4.601 270) (size 1.8 0.57) (layers "F.Cu" "F.Paste" "F.Mask")
      (net 9 "GND") (pinfunction "VSS") (pintype "passive"))
    (pad "172" smd rect (at 22.949 -4.601 270) (size 1.8 0.57) (layers "F.Cu" "F.Paste" "F.Mask")
      (net 281 "DQ17") (pinfunction "DQ17") (pintype "passive"))
    (pad "173" smd rect (at 23.8 -4.601 270) (size 1.8 0.57) (layers "F.Cu" "F.Paste" "F.Mask")
      (net 9 "GND") (pinfunction "VSS") (pintype "passive"))
    (pad "174" smd rect (at 24.649 -4.601 270) (size 1.8 0.57) (layers "F.Cu" "F.Paste" "F.Mask")
      (net 324 "DQS2_N") (pinfunction "DQS2_c") (pintype "passive"))
    (pad "175" smd rect (at 25.498 -4.601 270) (size 1.8 0.57) (layers "F.Cu" "F.Paste" "F.Mask")
      (net 322 "DQS2_P") (pinfunction "DQS2_t") (pintype "passive"))
    (pad "176" smd rect (at 26.35 -4.601 270) (size 1.8 0.57) (layers "F.Cu" "F.Paste" "F.Mask")
      (net 9 "GND") (pinfunction "VSS") (pintype "passive"))
    (pad "177" smd rect (at 27.199 -4.601 270) (size 1.8 0.57) (layers "F.Cu" "F.Paste" "F.Mask")
      (net 277 "DQ23") (pinfunction "DQ23") (pintype "passive"))
    (pad "178" smd rect (at 28.05 -4.601 270) (size 1.8 0.57) (layers "F.Cu" "F.Paste" "F.Mask")
      (net 9 "GND") (pinfunction "VSS") (pintype "passive"))
    (pad "179" smd rect (at 28.899 -4.601 270) (size 1.8 0.57) (layers "F.Cu" "F.Paste" "F.Mask")
      (net 286 "DQ19") (pinfunction "DQ19") (pintype "passive"))
    (pad "180" smd rect (at 29.749 -4.601 270) (size 1.8 0.57) (layers "F.Cu" "F.Paste" "F.Mask")
      (net 9 "GND") (pinfunction "VSS") (pintype "passive"))
    (pad "181" smd rect (at 30.6 -4.601 270) (size 1.8 0.57) (layers "F.Cu" "F.Paste" "F.Mask")
      (net 285 "DQ29") (pinfunction "DQ29") (pintype "passive"))
    (pad "182" smd rect (at 31.449 -4.601 270) (size 1.8 0.57) (layers "F.Cu" "F.Paste" "F.Mask")
      (net 9 "GND") (pinfunction "VSS") (pintype "passive"))
    (pad "183" smd rect (at 32.298 -4.601 270) (size 1.8 0.57) (layers "F.Cu" "F.Paste" "F.Mask")
      (net 271 "DQ25") (pinfunction "DQ25") (pintype "passive"))
    (pad "184" smd rect (at 33.149 -4.601 270) (size 1.8 0.57) (layers "F.Cu" "F.Paste" "F.Mask")
      (net 9 "GND") (pinfunction "VSS") (pintype "passive"))
    (pad "185" smd rect (at 33.999 -4.601 270) (size 1.8 0.57) (layers "F.Cu" "F.Paste" "F.Mask")
      (net 328 "DQS3_N") (pinfunction "DQS3_c") (pintype "passive"))
    (pad "186" smd rect (at 34.85 -4.601 270) (size 1.8 0.57) (layers "F.Cu" "F.Paste" "F.Mask")
      (net 326 "DQS3_P") (pinfunction "DQS3_t") (pintype "passive"))
    (pad "187" smd rect (at 35.7 -4.601 270) (size 1.8 0.57) (layers "F.Cu" "F.Paste" "F.Mask")
      (net 9 "GND") (pinfunction "VSS") (pintype "passive"))
    (pad "188" smd rect (at 36.548 -4.601 270) (size 1.8 0.57) (layers "F.Cu" "F.Paste" "F.Mask")
      (net 279 "DQ31") (pinfunction "DQ31") (pintype "passive"))
    (pad "189" smd rect (at 37.399 -4.601 270) (size 1.8 0.57) (layers "F.Cu" "F.Paste" "F.Mask")
      (net 9 "GND") (pinfunction "VSS") (pintype "passive"))
    (pad "190" smd rect (at 38.249 -4.601 270) (size 1.8 0.57) (layers "F.Cu" "F.Paste" "F.Mask")
      (net 287 "DQ27") (pinfunction "DQ27") (pintype "passive"))
    (pad "191" smd rect (at 39.1 -4.601 270) (size 1.8 0.57) (layers "F.Cu" "F.Paste" "F.Mask")
      (net 9 "GND") (pinfunction "VSS") (pintype "passive"))
    (pad "192" smd rect (at 39.95 -4.601 270) (size 1.8 0.57) (layers "F.Cu" "F.Paste" "F.Mask")
      (net 278 "CB5") (pinfunction "CB5") (pintype "passive"))
    (pad "193" smd rect (at 40.798 -4.601 270) (size 1.8 0.57) (layers "F.Cu" "F.Paste" "F.Mask")
      (net 9 "GND") (pinfunction "VSS") (pintype "passive"))
    (pad "194" smd rect (at 41.649 -4.601 270) (size 1.8 0.57) (layers "F.Cu" "F.Paste" "F.Mask")
      (net 272 "CB1") (pinfunction "CB1") (pintype "passive"))
    (pad "195" smd rect (at 42.499 -4.601 270) (size 1.8 0.57) (layers "F.Cu" "F.Paste" "F.Mask")
      (net 9 "GND") (pinfunction "VSS") (pintype "passive"))
    (pad "196" smd rect (at 43.35 -4.601 270) (size 1.8 0.57) (layers "F.Cu" "F.Paste" "F.Mask")
      (net 348 "DQS8_N") (pinfunction "DQS8_c") (pintype "passive"))
    (pad "197" smd rect (at 44.2 -4.601 270) (size 1.8 0.57) (layers "F.Cu" "F.Paste" "F.Mask")
      (net 346 "DQS8_P") (pinfunction "DQS8_t") (pintype "passive"))
    (pad "198" smd rect (at 45.048 -4.601 270) (size 1.8 0.57) (layers "F.Cu" "F.Paste" "F.Mask")
      (net 9 "GND") (pinfunction "VSS") (pintype "passive"))
    (pad "199" smd rect (at 45.898 -4.601 270) (size 1.8 0.57) (layers "F.Cu" "F.Paste" "F.Mask")
      (net 282 "CB7") (pinfunction "CB7") (pintype "passive"))
    (pad "200" smd rect (at 46.749 -4.601 270) (size 1.8 0.57) (layers "F.Cu" "F.Paste" "F.Mask")
      (net 9 "GND") (pinfunction "VSS") (pintype "passive"))
    (pad "201" smd rect (at 47.6 -4.601 270) (size 1.8 0.57) (layers "F.Cu" "F.Paste" "F.Mask")
      (net 295 "CB3") (pinfunction "CB3") (pintype "passive"))
    (pad "202" smd rect (at 48.45 -4.601 270) (size 1.8 0.57) (layers "F.Cu" "F.Paste" "F.Mask")
      (net 9 "GND") (pinfunction "VSS") (pintype "passive"))
    (pad "203" smd rect (at 49.298 -4.601 270) (size 1.8 0.57) (layers "F.Cu" "F.Paste" "F.Mask")
      (net 290 "CKE1\\NC") (pinfunction "CKE1") (pintype "passive"))
    (pad "204" smd rect (at 50.148 -4.601 270) (size 1.8 0.57) (layers "F.Cu" "F.Paste" "F.Mask")
      (net 77 "VDDQ") (pinfunction "VDD") (pintype "passive"))
    (pad "205" smd rect (at 50.999 -4.601 270) (size 1.8 0.57) (layers "F.Cu" "F.Paste" "F.Mask")
      (net 706 "unconnected-(U14B-RFU-Pad205)") (pinfunction "RFU") (pintype "no_connect"))
    (pad "206" smd rect (at 51.85 -4.601 270) (size 1.8 0.57) (layers "F.Cu" "F.Paste" "F.Mask")
      (net 77 "VDDQ") (pinfunction "VDD") (pintype "passive"))
    (pad "207" smd rect (at 52.7 -4.601 270) (size 1.8 0.57) (layers "F.Cu" "F.Paste" "F.Mask")
      (net 280 "BG1") (pinfunction "BG1") (pintype "passive"))
    (pad "208" smd rect (at 53.548 -4.601 270) (size 1.8 0.57) (layers "F.Cu" "F.Paste" "F.Mask")
      (net 296 "~{ALERT}") (pinfunction "ALERT_n") (pintype "passive"))
    (pad "209" smd rect (at 54.398 -4.601 270) (size 1.8 0.57) (layers "F.Cu" "F.Paste" "F.Mask")
      (net 77 "VDDQ") (pinfunction "VDD") (pintype "passive"))
    (pad "210" smd rect (at 55.249 -4.601 270) (size 1.8 0.57) (layers "F.Cu" "F.Paste" "F.Mask")
      (net 283 "A11") (pinfunction "A11") (pintype "passive"))
    (pad "211" smd rect (at 56.1 -4.601 270) (size 1.8 0.57) (layers "F.Cu" "F.Paste" "F.Mask")
      (net 284 "A7") (pinfunction "A7") (pintype "passive"))
    (pad "212" smd rect (at 56.95 -4.601 270) (size 1.8 0.57) (layers "F.Cu" "F.Paste" "F.Mask")
      (net 77 "VDDQ") (pinfunction "VDD") (pintype "passive"))
    (pad "213" smd rect (at 57.798 -4.601 270) (size 1.8 0.57) (layers "F.Cu" "F.Paste" "F.Mask")
      (net 276 "A5") (pinfunction "A5") (pintype "passive"))
    (pad "214" smd rect (at 58.648 -4.601 270) (size 1.8 0.57) (layers "F.Cu" "F.Paste" "F.Mask")
      (net 289 "A4") (pinfunction "A4") (pintype "passive"))
    (pad "215" smd rect (at 59.499 -4.601 270) (size 1.8 0.57) (layers "F.Cu" "F.Paste" "F.Mask")
      (net 77 "VDDQ") (pinfunction "VDD") (pintype "passive"))
    (pad "216" smd rect (at 60.35 -4.601 270) (size 1.8 0.57) (layers "F.Cu" "F.Paste" "F.Mask")
      (net 291 "A2") (pinfunction "A2") (pintype "passive"))
    (pad "217" smd rect (at 61.2 -4.601 270) (size 1.8 0.57) (layers "F.Cu" "F.Paste" "F.Mask")
      (net 77 "VDDQ") (pinfunction "VDD") (pintype "passive"))
    (pad "218" smd rect (at 62.048 -4.601 270) (size 1.8 0.57) (layers "F.Cu" "F.Paste" "F.Mask")
      (net 353 "CK1_P") (pinfunction "CK1_t") (pintype "passive"))
    (pad "219" smd rect (at 62.898 -4.601 270) (size 1.8 0.57) (layers "F.Cu" "F.Paste" "F.Mask")
      (net 354 "CK1_N") (pinfunction "CK1_c") (pintype "passive"))
    (pad "220" smd rect (at 63.749 -4.601 270) (size 1.8 0.57) (layers "F.Cu" "F.Paste" "F.Mask")
      (net 77 "VDDQ") (pinfunction "VDD") (pintype "passive"))
    (pad "221" smd rect (at 64.599 -4.601 270) (size 1.8 0.57) (layers "F.Cu" "F.Paste" "F.Mask")
      (net 186 "VTT") (pinfunction "VTT") (pintype "passive"))
    (pad "222" smd rect (at 70.549 -4.601 270) (size 1.8 0.57) (layers "F.Cu" "F.Paste" "F.Mask")
      (net 199 "PARITY") (pinfunction "PARITY") (pintype "passive"))
    (pad "223" smd rect (at 71.4 -4.601 270) (size 1.8 0.57) (layers "F.Cu" "F.Paste" "F.Mask")
      (net 77 "VDDQ") (pinfunction "VDD") (pintype "passive"))
    (pad "224" smd rect (at 72.248 -4.601 270) (size 1.8 0.57) (layers "F.Cu" "F.Paste" "F.Mask")
      (net 211 "BA1") (pinfunction "BA1") (pintype "passive"))
  )
)
